# T6G (Grand Teton) — schematic netlist excerpt (pin names and nets, part order shuffled) for the footprints in the layout excerpt that follows; sources: Cadence DE-HDL packaged netlist, KiCad conversion of 04192023_DAF0TMB3IC0_F0TG_MB_C_brd_V02_OCP.brd

R2845  Q_RES  33.2 1% CHIP  pkg 0402LF  page 81 : A = BMC_MONITER_R ; B = BMC_MONITER
PC85  Q_CAP  0.1UF 25V 10% X7R  pkg 0402  page 201 : A = P12V_AUX ; B = GND

(kicad_pcb
	(version 20260206)
	(generator "pcbnew")
	(generator_version "10.0")
	(general
		(thickness 1.6)
		(legacy_teardrops no)
	)
	(paper "A4")
	(title_block
		(title "04192023_DAF0TMB3IC0_F0TG_MB_C_brd_V02_OCP.brd")
		(comment 1 "Grand Teton / footprints 4625-4626 of 8354")
	)
	(layers
		(0 "F.Cu" signal "TOP")
		(4 "In1.Cu" signal "GND")
		(6 "In2.Cu" signal "IN1")
		(8 "In3.Cu" signal "GND1")
		(10 "In4.Cu" signal "IN2")
		(12 "In5.Cu" signal "GND2")
		(14 "In6.Cu" signal "IN3")
		(16 "In7.Cu" signal "GND3")
		(18 "In8.Cu" signal "VCC")
		(20 "In9.Cu" signal "VCC1")
		(22 "In10.Cu" signal "GND4")
		(24 "In11.Cu" signal "IN4")
		(26 "In12.Cu" signal "GND5")
		(28 "In13.Cu" signal "IN5")
		(30 "In14.Cu" signal "GND6")
		(32 "In15.Cu" signal "IN6")
		(34 "In16.Cu" signal "GND7")
		(2 "B.Cu" signal "BOTTOM")
		(9 "F.Adhes" user "F.Adhesive")
		(11 "B.Adhes" user "B.Adhesive")
		(13 "F.Paste" user "Package Geometry/Pastemask Top")
		(15 "B.Paste" user "Package Geometry/Pastemask Bottom")
		(5 "F.SilkS" user "Ref Des/Silkscreen Top")
		(7 "B.SilkS" user "Ref Des/Silkscreen Bottom")
		(1 "F.Mask" user "Board Geometry/Soldermask Top")
		(3 "B.Mask" user "Board Geometry/Soldermask Bottom")
		(17 "Dwgs.User" user "User.Drawings")
		(19 "Cmts.User" user "User.Comments")
		(21 "Eco1.User" user "User.Eco1")
		(23 "Eco2.User" user "User.Eco2")
		(25 "Edge.Cuts" user "Board Geometry/Outline")
		(27 "Margin" user)
		(31 "F.CrtYd" user "Package Geometry/Place Bound Top")
		(29 "B.CrtYd" user "Package Geometry/Place Bound Bottom")
		(35 "F.Fab" user "Ref Des/Assembly Top")
		(33 "B.Fab" user "Ref Des/Assembly Bottom")
	)
	(footprint ""
		(layer "F.Cu")
		(at 335.264252 -357.703628 180)
		(property "Reference" "PC85"
			(at 0 0 180)
			(layer "F.SilkS")
			(hide yes)
			(effects
				(font
					(size 1.27 1.27)
				)
			)
		)
		(property "Value" ""
			(at 0 0 180)
			(layer "F.Fab")
			(effects
				(font
					(size 1.27 1.27)
				)
			)
		)
		(duplicate_pad_numbers_are_jumpers no)
		(fp_line
			(start 0.7874 0.4064)
			(end -0.7874 0.4064)
			(stroke
				(width 0.1524)
				(type default)
			)
			(layer "F.SilkS")
		)
		(fp_line
			(start 0.7874 -0.4064)
			(end 0.7874 0.4064)
			(stroke
				(width 0.1524)
				(type default)
			)
			(layer "F.SilkS")
		)
		(fp_line
			(start -0.7874 0.4064)
			(end -0.7874 -0.4064)
			(stroke
				(width 0.1524)
				(type default)
			)
			(layer "F.SilkS")
		)
		(fp_line
			(start -0.7874 -0.4064)
			(end 0.7874 -0.4064)
			(stroke
				(width 0.1524)
				(type default)
			)
			(layer "F.SilkS")
		)
		(fp_line
			(start 0.67945 0.3048)
			(end 0.120396 0.3048)
			(stroke
				(width 0.1)
				(type default)
			)
			(layer "F.Fab")
		)
		(fp_line
			(start 0.67945 -0.3048)
			(end 0.67945 0.3048)
			(stroke
				(width 0.1)
				(type default)
			)
			(layer "F.Fab")
		)
		(fp_line
			(start 0.12065 -0.2794)
			(end 0.12065 -0.3048)
			(stroke
				(width 0.1)
				(type default)
			)
			(layer "F.Fab")
		)
		(fp_line
			(start 0.12065 -0.3048)
			(end 0.67945 -0.3048)
			(stroke
				(width 0.1)
				(type default)
			)
			(layer "F.Fab")
		)
		(fp_line
			(start 0.120396 0.3048)
			(end 0.120396 0.2794)
			(stroke
				(width 0.1)
				(type default)
			)
			(layer "F.Fab")
		)
		(fp_line
			(start 0.120396 0.2794)
			(end -0.12065 0.2794)
			(stroke
				(width 0.1)
				(type default)
			)
			(layer "F.Fab")
		)
		(fp_line
			(start -0.12065 0.3048)
			(end -0.67945 0.3048)
			(stroke
				(width 0.1)
				(type default)
			)
			(layer "F.Fab")
		)
		(fp_line
			(start -0.12065 0.2794)
			(end -0.12065 0.3048)
			(stroke
				(width 0.1)
				(type default)
			)
			(layer "F.Fab")
		)
		(fp_line
			(start -0.12065 -0.2794)
			(end 0.12065 -0.2794)
			(stroke
				(width 0.1)
				(type default)
			)
			(layer "F.Fab")
		)
		(fp_line
			(start -0.12065 -0.305054)
			(end -0.12065 -0.2794)
			(stroke
				(width 0.1)
				(type default)
			)
			(layer "F.Fab")
		)
		(fp_line
			(start -0.67945 0.3048)
			(end -0.67945 -0.305054)
			(stroke
				(width 0.1)
				(type default)
			)
			(layer "F.Fab")
		)
		(fp_line
			(start -0.67945 -0.305054)
			(end -0.12065 -0.305054)
			(stroke
				(width 0.1)
				(type default)
			)
			(layer "F.Fab")
		)
		(pad "1" smd circle
			(at -0.40005 0 180)
			(size 0 0)
			(layers "F.Cu" "F.Mask" "F.Paste")
			(net "P12V_AUX")
		)
		(pad "2" smd circle
			(at 0.40005 0 180)
			(size 0 0)
			(layers "F.Cu" "F.Mask" "F.Paste")
			(net "GND")
		)
	)
	(footprint ""
		(layer "F.Cu")
		(at 208.894426 -110.649512 180)
		(property "Reference" "R2845"
			(at 0 0 180)
			(layer "F.SilkS")
			(hide yes)
			(effects
				(font
					(size 1.27 1.27)
				)
			)
		)
		(property "Value" ""
			(at 0 0 180)
			(layer "F.Fab")
			(effects
				(font
					(size 1.27 1.27)
				)
			)
		)
		(duplicate_pad_numbers_are_jumpers no)
		(fp_line
			(start 0.7874 0.4064)
			(end -0.7874 0.4064)
			(stroke
				(width 0.1524)
				(type default)
			)
			(layer "F.SilkS")
		)
		(fp_line
			(start 0.7874 -0.4064)
			(end 0.7874 0.4064)
			(stroke
				(width 0.1524)
				(type default)
			)
			(layer "F.SilkS")
		)
		(fp_line
			(start -0.7874 0.4064)
			(end -0.7874 -0.4064)
			(stroke
				(width 0.1524)
				(type default)
			)
			(layer "F.SilkS")
		)
		(fp_line
			(start -0.7874 -0.4064)
			(end 0.7874 -0.4064)
			(stroke
				(width 0.1524)
				(type default)
			)
			(layer "F.SilkS")
		)
		(fp_line
			(start 0.67945 0.3048)
			(end 0.120396 0.3048)
			(stroke
				(width 0.1)
				(type default)
			)
			(layer "F.Fab")
		)
		(fp_line
			(start 0.67945 -0.3048)
			(end 0.67945 0.3048)
			(stroke
				(width 0.1)
				(type default)
			)
			(layer "F.Fab")
		)
		(fp_line
			(start 0.12065 -0.2794)
			(end 0.12065 -0.3048)
			(stroke
				(width 0.1)
				(type default)
			)
			(layer "F.Fab")
		)
		(fp_line
			(start 0.12065 -0.3048)
			(end 0.67945 -0.3048)
			(stroke
				(width 0.1)
				(type default)
			)
			(layer "F.Fab")
		)
		(fp_line
			(start 0.120396 0.3048)
			(end 0.120396 0.2794)
			(stroke
				(width 0.1)
				(type default)
			)
			(layer "F.Fab")
		)
		(fp_line
			(start 0.120396 0.2794)
			(end -0.12065 0.2794)
			(stroke
				(width 0.1)
				(type default)
			)
			(layer "F.Fab")
		)
		(fp_line
			(start -0.12065 0.3048)
			(end -0.67945 0.3048)
			(stroke
				(width 0.1)
				(type default)
			)
			(layer "F.Fab")
		)
		(fp_line
			(start -0.12065 0.2794)
			(end -0.12065 0.3048)
			(stroke
				(width 0.1)
				(type default)
			)
			(layer "F.Fab")
		)
		(fp_line
			(start -0.12065 -0.2794)
			(end 0.12065 -0.2794)
			(stroke
				(width 0.1)
				(type default)
			)
			(layer "F.Fab")
		)
		(fp_line
			(start -0.12065 -0.305054)
			(end -0.12065 -0.2794)
			(stroke
				(width 0.1)
				(type default)
			)
			(layer "F.Fab")
		)
		(fp_line
			(start -0.67945 0.3048)
			(end -0.67945 -0.305054)
			(stroke
				(width 0.1)
				(type default)
			)
			(layer "F.Fab")
		)
		(fp_line
			(start -0.67945 -0.305054)
			(end -0.12065 -0.305054)
			(stroke
				(width 0.1)
				(type default)
			)
			(layer "F.Fab")
		)
		(pad "1" smd circle
			(at -0.40005 0 180)
			(size 0 0)
			(layers "F.Cu" "F.Mask" "F.Paste")
			(net "BMC_MONITER_R")
		)
		(pad "2" smd circle
			(at 0.40005 0 180)
			(size 0 0)
			(layers "F.Cu" "F.Mask" "F.Paste")
			(net "BMC_MONITER")
		)
	)
)
